(kicad_pcb
	(version 20260206)
	(generator "pcbnew")
	(generator_version "10.0")
	(general
		(thickness 1.6)
		(legacy_teardrops no)
	)
	(paper "A4")
	(title_block
		(title "peb — Lightning_PEB_BRD.brd")
		(comment 1 "Lightning (Wiwynn / Facebook NVMe JBOF) / footprints 678-684 of 2563")
	)
	(layers
		(0 "F.Cu" signal "TOP")
		(4 "In1.Cu" signal "L2GND")
		(6 "In2.Cu" signal "L3")
		(8 "In3.Cu" signal "L4VCC")
		(10 "In4.Cu" signal "L5VCC")
		(12 "In5.Cu" signal "L6")
		(14 "In6.Cu" signal "L7GND")
		(2 "B.Cu" signal "BOTTOM")
		(9 "F.Adhes" user "F.Adhesive")
		(11 "B.Adhes" user "B.Adhesive")
		(13 "F.Paste" user "Package Geometry/Pastemask Top")
		(15 "B.Paste" user "Package Geometry/Pastemask Bottom")
		(5 "F.SilkS" user "Ref Des/Silkscreen Top")
		(7 "B.SilkS" user "Ref Des/Silkscreen Bottom")
		(1 "F.Mask" user "Board Geometry/Soldermask Top")
		(3 "B.Mask" user "Board Geometry/Soldermask Bottom")
		(17 "Dwgs.User" user "User.Drawings")
		(19 "Cmts.User" user "User.Comments")
		(21 "Eco1.User" user "User.Eco1")
		(23 "Eco2.User" user "User.Eco2")
		(25 "Edge.Cuts" user "Board Geometry/Outline")
		(27 "Margin" user)
		(31 "F.CrtYd" user "Package Geometry/Place Bound Top")
		(29 "B.CrtYd" user "Package Geometry/Place Bound Bottom")
		(35 "F.Fab" user "Ref Des/Assembly Top")
		(33 "B.Fab" user "Ref Des/Assembly Bottom")
	)
	(footprint ""
		(layer "F.Cu")
		(at 72.0852 -163.5506 -90)
		(property "Reference" "PR17"
			(at 0 0 270)
			(layer "F.SilkS")
			(hide yes)
			(effects
				(font
					(size 1.27 1.27)
				)
			)
		)
		(property "Value" "0R2J-2-GP"
			(at 0.064008 -3.993896 270)
			(unlocked yes)
			(layer "F.Fab")
			(hide yes)
			(effects
				(font
					(size 1.016 1.016)
					(thickness 0.1524)
				)
			)
		)
		(property "Device Type" "R402H16"
			(at 0.064008 -5.517896 270)
			(unlocked yes)
			(layer "F.Fab")
			(hide yes)
			(effects
				(font
					(size 1.016 1.016)
					(thickness 0.1524)
				)
			)
		)
		(duplicate_pad_numbers_are_jumpers no)
		(fp_line
			(start -0.508 -0.9398)
			(end -0.508 0.9398)
			(stroke
				(width 0.1524)
				(type default)
			)
			(layer "F.SilkS")
		)
		(fp_line
			(start 0.508 -0.9398)
			(end -0.508 -0.9398)
			(stroke
				(width 0.1524)
				(type default)
			)
			(layer "F.SilkS")
		)
		(fp_rect
			(start -0.508 0.9398)
			(end 0.508 -0.9398)
			(stroke
				(width 0)
				(type default)
			)
			(fill no)
			(layer "F.CrtYd")
		)
		(fp_rect
			(start -0.508 0.9398)
			(end 0.508 -0.9398)
			(stroke
				(width 0)
				(type default)
			)
			(fill no)
			(layer "F.Fab")
		)
		(pad "1" smd custom
			(at 0 -0.4445 270)
			(size 0.1397 0.1397)
			(layers "F.Cu" "F.Mask" "F.Paste")
			(net "P5V_STBY")
			(options
				(clearance outline)
				(anchor circle)
			)
			(primitives
				(gr_poly
					(pts
						(arc
							(start -0.1778 -0.2794)
							(mid -0.249642 -0.249642)
							(end -0.2794 -0.1778)
						)
						(arc
							(start -0.2794 0.1778)
							(mid -0.249642 0.249642)
							(end -0.1778 0.2794)
						)
						(arc
							(start 0.1778 0.2794)
							(mid 0.249642 0.249642)
							(end 0.2794 0.1778)
						)
						(arc
							(start 0.2794 -0.1778)
							(mid 0.249642 -0.249642)
							(end 0.1778 -0.2794)
						)
					)
					(width 0)
					(fill yes)
				)
			)
		)
		(pad "2" smd custom
			(at 0 0.4445 270)
			(size 0.1397 0.1397)
			(layers "F.Cu" "F.Mask" "F.Paste")
			(net "VR_P1V538_STBY_BIAS")
			(options
				(clearance outline)
				(anchor circle)
			)
			(primitives
				(gr_poly
					(pts
						(arc
							(start -0.1778 -0.2794)
							(mid -0.249642 -0.249642)
							(end -0.2794 -0.1778)
						)
						(arc
							(start -0.2794 0.1778)
							(mid -0.249642 0.249642)
							(end -0.1778 0.2794)
						)
						(arc
							(start 0.1778 0.2794)
							(mid 0.249642 0.249642)
							(end 0.2794 0.1778)
						)
						(arc
							(start 0.2794 -0.1778)
							(mid 0.249642 -0.249642)
							(end 0.1778 -0.2794)
						)
					)
					(width 0)
					(fill yes)
				)
			)
		)
	)
	(footprint ""
		(layer "F.Cu")
		(at 126.721362 -42.390568 180)
		(property "Reference" "R622"
			(at 0 0 180)
			(layer "F.SilkS")
			(hide yes)
			(effects
				(font
					(size 1.27 1.27)
				)
			)
		)
		(property "Value" "0R2J-2-GP"
			(at 0.064008 -3.993896 180)
			(unlocked yes)
			(layer "F.Fab")
			(hide yes)
			(effects
				(font
					(size 1.016 1.016)
					(thickness 0.1524)
				)
			)
		)
		(property "Device Type" "R402H16"
			(at 0.064008 -5.517896 180)
			(unlocked yes)
			(layer "F.Fab")
			(hide yes)
			(effects
				(font
					(size 1.016 1.016)
					(thickness 0.1524)
				)
			)
		)
		(duplicate_pad_numbers_are_jumpers no)
		(fp_line
			(start 0.508 -0.9398)
			(end -0.508 -0.9398)
			(stroke
				(width 0.1524)
				(type default)
			)
			(layer "F.SilkS")
		)
		(fp_line
			(start -0.508 -0.9398)
			(end -0.508 0.9398)
			(stroke
				(width 0.1524)
				(type default)
			)
			(layer "F.SilkS")
		)
		(fp_rect
			(start -0.508 0.9398)
			(end 0.508 -0.9398)
			(stroke
				(width 0)
				(type default)
			)
			(fill no)
			(layer "F.CrtYd")
		)
		(fp_rect
			(start -0.508 0.9398)
			(end 0.508 -0.9398)
			(stroke
				(width 0)
				(type default)
			)
			(fill no)
			(layer "F.Fab")
		)
		(pad "1" smd custom
			(at 0 -0.4445 180)
			(size 0.1397 0.1397)
			(layers "F.Cu" "F.Mask" "F.Paste")
			(net "UPLINK3_R")
			(options
				(clearance outline)
				(anchor circle)
			)
			(primitives
				(gr_poly
					(pts
						(arc
							(start -0.1778 -0.2794)
							(mid -0.249642 -0.249642)
							(end -0.2794 -0.1778)
						)
						(arc
							(start -0.2794 0.1778)
							(mid -0.249642 0.249642)
							(end -0.1778 0.2794)
						)
						(arc
							(start 0.1778 0.2794)
							(mid 0.249642 0.249642)
							(end 0.2794 0.1778)
						)
						(arc
							(start 0.2794 -0.1778)
							(mid 0.249642 -0.249642)
							(end 0.1778 -0.2794)
						)
					)
					(width 0)
					(fill yes)
				)
			)
		)
		(pad "2" smd custom
			(at 0 0.4445 180)
			(size 0.1397 0.1397)
			(layers "F.Cu" "F.Mask" "F.Paste")
			(net "UPLINK3")
			(options
				(clearance outline)
				(anchor circle)
			)
			(primitives
				(gr_poly
					(pts
						(arc
							(start -0.1778 -0.2794)
							(mid -0.249642 -0.249642)
							(end -0.2794 -0.1778)
						)
						(arc
							(start -0.2794 0.1778)
							(mid -0.249642 0.249642)
							(end -0.1778 0.2794)
						)
						(arc
							(start 0.1778 0.2794)
							(mid 0.249642 0.249642)
							(end 0.2794 0.1778)
						)
						(arc
							(start 0.2794 -0.1778)
							(mid 0.249642 -0.249642)
							(end 0.1778 -0.2794)
						)
					)
					(width 0)
					(fill yes)
				)
			)
		)
	)
	(footprint ""
		(layer "F.Cu")
		(at 20.955 -138.7602 -90)
		(property "Reference" "R645"
			(at 0 0 270)
			(layer "F.SilkS")
			(hide yes)
			(effects
				(font
					(size 1.27 1.27)
				)
			)
		)
		(property "Value" "0R2J-2-GP"
			(at 0.064008 -3.993896 270)
			(unlocked yes)
			(layer "F.Fab")
			(hide yes)
			(effects
				(font
					(size 1.016 1.016)
					(thickness 0.1524)
				)
			)
		)
		(property "Device Type" "R402H16"
			(at 0.064008 -5.517896 270)
			(unlocked yes)
			(layer "F.Fab")
			(hide yes)
			(effects
				(font
					(size 1.016 1.016)
					(thickness 0.1524)
				)
			)
		)
		(duplicate_pad_numbers_are_jumpers no)
		(fp_line
			(start -0.508 -0.9398)
			(end -0.508 0.9398)
			(stroke
				(width 0.1524)
				(type default)
			)
			(layer "F.SilkS")
		)
		(fp_line
			(start 0.508 -0.9398)
			(end -0.508 -0.9398)
			(stroke
				(width 0.1524)
				(type default)
			)
			(layer "F.SilkS")
		)
		(fp_rect
			(start -0.508 0.9398)
			(end 0.508 -0.9398)
			(stroke
				(width 0)
				(type default)
			)
			(fill no)
			(layer "F.CrtYd")
		)
		(fp_rect
			(start -0.508 0.9398)
			(end 0.508 -0.9398)
			(stroke
				(width 0)
				(type default)
			)
			(fill no)
			(layer "F.Fab")
		)
		(pad "1" smd custom
			(at 0 -0.4445 270)
			(size 0.1397 0.1397)
			(layers "F.Cu" "F.Mask" "F.Paste")
			(net "GPIOR2_R")
			(options
				(clearance outline)
				(anchor circle)
			)
			(primitives
				(gr_poly
					(pts
						(arc
							(start -0.1778 -0.2794)
							(mid -0.249642 -0.249642)
							(end -0.2794 -0.1778)
						)
						(arc
							(start -0.2794 0.1778)
							(mid -0.249642 0.249642)
							(end -0.1778 0.2794)
						)
						(arc
							(start 0.1778 0.2794)
							(mid 0.249642 0.249642)
							(end 0.2794 0.1778)
						)
						(arc
							(start 0.2794 -0.1778)
							(mid 0.249642 -0.249642)
							(end 0.1778 -0.2794)
						)
					)
					(width 0)
					(fill yes)
				)
			)
		)
		(pad "2" smd custom
			(at 0 0.4445 270)
			(size 0.1397 0.1397)
			(layers "F.Cu" "F.Mask" "F.Paste")
			(net "TRAY_ID2")
			(options
				(clearance outline)
				(anchor circle)
			)
			(primitives
				(gr_poly
					(pts
						(arc
							(start -0.1778 -0.2794)
							(mid -0.249642 -0.249642)
							(end -0.2794 -0.1778)
						)
						(arc
							(start -0.2794 0.1778)
							(mid -0.249642 0.249642)
							(end -0.1778 0.2794)
						)
						(arc
							(start 0.1778 0.2794)
							(mid 0.249642 0.249642)
							(end 0.2794 0.1778)
						)
						(arc
							(start 0.2794 -0.1778)
							(mid 0.249642 -0.249642)
							(end 0.1778 -0.2794)
						)
					)
					(width 0)
					(fill yes)
				)
			)
		)
	)
	(footprint ""
		(layer "F.Cu")
		(at 22.733 -160.528 180)
		(property "Reference" "U35"
			(at 0 0 180)
			(layer "F.SilkS")
			(hide yes)
			(effects
				(font
					(size 1.27 1.27)
				)
			)
		)
		(property "Value" "SN74LVC1G07DCKRG4-2-GP"
			(at -2.3368 -8.6868 180)
			(unlocked yes)
			(layer "F.Fab")
			(hide yes)
			(effects
				(font
					(size 1.016 1.016)
					(thickness 0.1524)
				)
			)
		)
		(property "Device Type" "SC70-5H44"
			(at -2.3114 -10.414 180)
			(unlocked yes)
			(layer "F.Fab")
			(hide yes)
			(effects
				(font
					(size 1.016 1.016)
					(thickness 0.1524)
				)
			)
		)
		(duplicate_pad_numbers_are_jumpers no)
		(fp_line
			(start 1.3843 -1.8034)
			(end 1.3843 -1.1176)
			(stroke
				(width 0.3302)
				(type default)
			)
			(layer "F.SilkS")
		)
		(fp_line
			(start 1.27 1.7018)
			(end -1.27 1.7018)
			(stroke
				(width 0.1524)
				(type default)
			)
			(layer "F.SilkS")
		)
		(fp_line
			(start 1.27 -1.7018)
			(end 1.27 1.7018)
			(stroke
				(width 0.1524)
				(type default)
			)
			(layer "F.SilkS")
		)
		(fp_line
			(start 0.6604 -1.8034)
			(end 1.3843 -1.8034)
			(stroke
				(width 0.3302)
				(type default)
			)
			(layer "F.SilkS")
		)
		(fp_line
			(start -1.27 1.7018)
			(end -1.27 -1.7018)
			(stroke
				(width 0.1524)
				(type default)
			)
			(layer "F.SilkS")
		)
		(fp_line
			(start -1.27 -1.7018)
			(end 1.27 -1.7018)
			(stroke
				(width 0.1524)
				(type default)
			)
			(layer "F.SilkS")
		)
		(fp_rect
			(start -1.524 1.9558)
			(end 1.524 -1.9558)
			(stroke
				(width 0)
				(type default)
			)
			(fill no)
			(layer "F.CrtYd")
		)
		(fp_poly
			(pts
				(xy -1.524 -1.9558) (xy 1.524 -1.9558) (xy 1.524 1.9558) (xy -1.524 1.9558)
			)
			(stroke
				(width 0)
				(type default)
			)
			(fill no)
			(layer "F.Fab")
		)
		(pad "1" smd rect
			(at 0.65024 -0.8255 180)
			(size 0.4064 1.2192)
			(layers "F.Cu" "F.Mask" "F.Paste")
			(net "Net_516")
		)
		(pad "2" smd rect
			(at 0 -0.8255 180)
			(size 0.4064 1.2192)
			(layers "F.Cu" "F.Mask" "F.Paste")
			(net "BMC_RESET#_DDR3")
		)
		(pad "3" smd rect
			(at -0.65024 -0.8255 180)
			(size 0.4064 1.2192)
			(layers "F.Cu" "F.Mask" "F.Paste")
			(net "GND")
		)
		(pad "4" smd rect
			(at -0.65024 0.8255 180)
			(size 0.4064 1.2192)
			(layers "F.Cu" "F.Mask" "F.Paste")
			(net "BMC_RESET#_DDR3_BUF")
		)
		(pad "5" smd rect
			(at 0.65024 0.8255 180)
			(size 0.4064 1.2192)
			(layers "F.Cu" "F.Mask" "F.Paste")
			(net "P3V3_STBY")
		)
	)
	(footprint ""
		(layer "F.Cu")
		(at 43.457876 -61.204094 180)
		(property "Reference" "R635"
			(at 0 0 180)
			(layer "F.SilkS")
			(hide yes)
			(effects
				(font
					(size 1.27 1.27)
				)
			)
		)
		(property "Value" "0R3J-0-U-GP"
			(at -0.0254 -2.5146 180)
			(unlocked yes)
			(layer "F.Fab")
			(hide yes)
			(effects
				(font
					(size 1.016 1.016)
					(thickness 0.1524)
				)
			)
		)
		(property "Device Type" "R603H22"
			(at -0.0254 -4.0386 180)
			(unlocked yes)
			(layer "F.Fab")
			(hide yes)
			(effects
				(font
					(size 1.016 1.016)
					(thickness 0.1524)
				)
			)
		)
		(duplicate_pad_numbers_are_jumpers no)
		(fp_line
			(start 0.2032 0)
			(end 0.4826 0)
			(stroke
				(width 0.2032)
				(type default)
			)
			(layer "F.SilkS")
		)
		(fp_line
			(start -0.4826 0)
			(end -0.2032 0)
			(stroke
				(width 0.2032)
				(type default)
			)
			(layer "F.SilkS")
		)
		(fp_rect
			(start -0.5842 1.3335)
			(end 0.5842 -1.3335)
			(stroke
				(width 0)
				(type default)
			)
			(fill no)
			(layer "F.CrtYd")
		)
		(fp_rect
			(start -0.5842 1.3335)
			(end 0.5842 -1.3335)
			(stroke
				(width 0)
				(type default)
			)
			(fill no)
			(layer "F.Fab")
		)
		(pad "1" smd custom
			(at 0 -0.762 180)
			(size 0.2159 0.2159)
			(layers "F.Cu" "F.Mask" "F.Paste")
			(net "USB5V_EN")
			(options
				(clearance outline)
				(anchor circle)
			)
			(primitives
				(gr_poly
					(pts
						(arc
							(start -0.3302 -0.4318)
							(mid -0.402042 -0.402042)
							(end -0.4318 -0.3302)
						)
						(arc
							(start -0.4318 0.3302)
							(mid -0.402042 0.402042)
							(end -0.3302 0.4318)
						)
						(arc
							(start 0.3302 0.4318)
							(mid 0.402042 0.402042)
							(end 0.4318 0.3302)
						)
						(arc
							(start 0.4318 -0.3302)
							(mid 0.402042 -0.402042)
							(end 0.3302 -0.4318)
						)
					)
					(width 0)
					(fill yes)
				)
			)
		)
		(pad "2" smd custom
			(at 0 0.762 180)
			(size 0.2159 0.2159)
			(layers "F.Cu" "F.Mask" "F.Paste")
			(net "BMC_USB_EN_1")
			(options
				(clearance outline)
				(anchor circle)
			)
			(primitives
				(gr_poly
					(pts
						(arc
							(start -0.3302 -0.4318)
							(mid -0.402042 -0.402042)
							(end -0.4318 -0.3302)
						)
						(arc
							(start -0.4318 0.3302)
							(mid -0.402042 0.402042)
							(end -0.3302 0.4318)
						)
						(arc
							(start 0.3302 0.4318)
							(mid 0.402042 0.402042)
							(end 0.4318 0.3302)
						)
						(arc
							(start 0.4318 -0.3302)
							(mid 0.402042 -0.402042)
							(end 0.3302 -0.4318)
						)
					)
					(width 0)
					(fill yes)
				)
			)
		)
	)
	(footprint ""
		(layer "F.Cu")
		(at 159.807402 -54.231032 90)
		(property "Reference" "R79"
			(at 0 0 90)
			(layer "F.SilkS")
			(hide yes)
			(effects
				(font
					(size 1.27 1.27)
				)
			)
		)
		(property "Value" "0R2J-2-GP"
			(at 0.064008 -3.993896 90)
			(unlocked yes)
			(layer "F.Fab")
			(hide yes)
			(effects
				(font
					(size 1.016 1.016)
					(thickness 0.1524)
				)
			)
		)
		(property "Device Type" "R402H16"
			(at 0.064008 -5.517896 90)
			(unlocked yes)
			(layer "F.Fab")
			(hide yes)
			(effects
				(font
					(size 1.016 1.016)
					(thickness 0.1524)
				)
			)
		)
		(duplicate_pad_numbers_are_jumpers no)
		(fp_line
			(start 0.508 -0.9398)
			(end -0.508 -0.9398)
			(stroke
				(width 0.1524)
				(type default)
			)
			(layer "F.SilkS")
		)
		(fp_line
			(start -0.508 -0.9398)
			(end -0.508 0.9398)
			(stroke
				(width 0.1524)
				(type default)
			)
			(layer "F.SilkS")
		)
		(fp_rect
			(start -0.508 0.9398)
			(end 0.508 -0.9398)
			(stroke
				(width 0)
				(type default)
			)
			(fill no)
			(layer "F.CrtYd")
		)
		(fp_rect
			(start -0.508 0.9398)
			(end 0.508 -0.9398)
			(stroke
				(width 0)
				(type default)
			)
			(fill no)
			(layer "F.Fab")
		)
		(pad "1" smd custom
			(at 0 -0.4445 90)
			(size 0.1397 0.1397)
			(layers "F.Cu" "F.Mask" "F.Paste")
			(net "P0V9_VFB_R")
			(options
				(clearance outline)
				(anchor circle)
			)
			(primitives
				(gr_poly
					(pts
						(arc
							(start -0.1778 -0.2794)
							(mid -0.249642 -0.249642)
							(end -0.2794 -0.1778)
						)
						(arc
							(start -0.2794 0.1778)
							(mid -0.249642 0.249642)
							(end -0.1778 0.2794)
						)
						(arc
							(start 0.1778 0.2794)
							(mid 0.249642 0.249642)
							(end 0.2794 0.1778)
						)
						(arc
							(start 0.2794 -0.1778)
							(mid 0.249642 -0.249642)
							(end 0.1778 -0.2794)
						)
					)
					(width 0)
					(fill yes)
				)
			)
		)
		(pad "2" smd custom
			(at 0 0.4445 90)
			(size 0.1397 0.1397)
			(layers "F.Cu" "F.Mask" "F.Paste")
			(net "DUT_AVD_TX")
			(options
				(clearance outline)
				(anchor circle)
			)
			(primitives
				(gr_poly
					(pts
						(arc
							(start -0.1778 -0.2794)
							(mid -0.249642 -0.249642)
							(end -0.2794 -0.1778)
						)
						(arc
							(start -0.2794 0.1778)
							(mid -0.249642 0.249642)
							(end -0.1778 0.2794)
						)
						(arc
							(start 0.1778 0.2794)
							(mid 0.249642 0.249642)
							(end 0.2794 0.1778)
						)
						(arc
							(start 0.2794 -0.1778)
							(mid 0.249642 -0.249642)
							(end 0.1778 -0.2794)
						)
					)
					(width 0)
					(fill yes)
				)
			)
		)
	)
	(footprint ""
		(layer "F.Cu")
		(at 90.2208 -83.947)
		(property "Reference" "SR842"
			(at 0 0 0)
			(layer "F.SilkS")
			(hide yes)
			(effects
				(font
					(size 1.27 1.27)
				)
			)
		)
		(property "Value" "10KR2F-2-GP"
			(at 0.064008 -3.993896 0)
			(unlocked yes)
			(layer "F.Fab")
			(hide yes)
			(effects
				(font
					(size 1.016 1.016)
					(thickness 0.1524)
				)
			)
		)
		(property "Device Type" "R402H16"
			(at 0.064008 -5.517896 0)
			(unlocked yes)
			(layer "F.Fab")
			(hide yes)
			(effects
				(font
					(size 1.016 1.016)
					(thickness 0.1524)
				)
			)
		)
		(duplicate_pad_numbers_are_jumpers no)
		(fp_line
			(start -0.508 -0.9398)
			(end -0.508 0.9398)
			(stroke
				(width 0.1524)
				(type default)
			)
			(layer "F.SilkS")
		)
		(fp_line
			(start 0.508 -0.9398)
			(end -0.508 -0.9398)
			(stroke
				(width 0.1524)
				(type default)
			)
			(layer "F.SilkS")
		)
		(fp_rect
			(start -0.508 0.9398)
			(end 0.508 -0.9398)
			(stroke
				(width 0)
				(type default)
			)
			(fill no)
			(layer "F.CrtYd")
		)
		(fp_rect
			(start -0.508 0.9398)
			(end 0.508 -0.9398)
			(stroke
				(width 0)
				(type default)
			)
			(fill no)
			(layer "F.Fab")
		)
		(pad "1" smd custom
			(at 0 -0.4445)
			(size 0.1397 0.1397)
			(layers "F.Cu" "F.Mask" "F.Paste")
			(net "P1V8_STBY")
			(options
				(clearance outline)
				(anchor circle)
			)
			(primitives
				(gr_poly
					(pts
						(arc
							(start -0.1778 -0.2794)
							(mid -0.249642 -0.249642)
							(end -0.2794 -0.1778)
						)
						(arc
							(start -0.2794 0.1778)
							(mid -0.249642 0.249642)
							(end -0.1778 0.2794)
						)
						(arc
							(start 0.1778 0.2794)
							(mid 0.249642 0.249642)
							(end 0.2794 0.1778)
						)
						(arc
							(start 0.2794 -0.1778)
							(mid 0.249642 -0.249642)
							(end 0.1778 -0.2794)
						)
					)
					(width 0)
					(fill yes)
				)
			)
		)
		(pad "2" smd custom
			(at 0 0.4445)
			(size 0.1397 0.1397)
			(layers "F.Cu" "F.Mask" "F.Paste")
			(net "SMART_UART_EN")
			(options
				(clearance outline)
				(anchor circle)
			)
			(primitives
				(gr_poly
					(pts
						(arc
							(start -0.1778 -0.2794)
							(mid -0.249642 -0.249642)
							(end -0.2794 -0.1778)
						)
						(arc
							(start -0.2794 0.1778)
							(mid -0.249642 0.249642)
							(end -0.1778 0.2794)
						)
						(arc
							(start 0.1778 0.2794)
							(mid 0.249642 0.249642)
							(end 0.2794 0.1778)
						)
						(arc
							(start 0.2794 -0.1778)
							(mid 0.249642 -0.249642)
							(end 0.1778 -0.2794)
						)
					)
					(width 0)
					(fill yes)
				)
			)
		)
	)
)
